# S9S_MB_2U (Grand Teton) — schematic netlist excerpt (pin names and nets, part order shuffled) for the footprints in the layout excerpt that follows; sources: Cadence DE-HDL packaged netlist, KiCad conversion of 03242023_DA0F0TMBIJ0_F0T_Motherboard_J_brd_V01_OCP.brd

X42  TP_TDR_4P_FTS  TP_TDR_4P_DIP EMPTY  pkg TH  page 310
  S1  = UNNAMED_310_TPTDR4PFTS_I10_S1
  P1  = T1_GND
  P2  = T1_GND
  S2  = UNNAMED_310_TPTDR4PFTS_I10_S2

PC27  Q_CAP  3300PF 50V 10% X7R  pkg 0402  page 282 : A = PVNN_MAIN_CPU0_REF ; B = GND

(kicad_pcb
	(version 20260206)
	(generator "pcbnew")
	(generator_version "10.0")
	(general
		(thickness 1.6)
		(legacy_teardrops no)
	)
	(paper "A4")
	(title_block
		(title "03242023_DA0F0TMBIJ0_F0T_Motherboard_J_brd_V01_OCP.brd")
		(comment 1 "Grand Teton / footprints 2554-2555 of 6105")
	)
	(layers
		(0 "F.Cu" signal "TOP")
		(4 "In1.Cu" signal "GND")
		(6 "In2.Cu" signal "IN1")
		(8 "In3.Cu" signal "GND1")
		(10 "In4.Cu" signal "IN2")
		(12 "In5.Cu" signal "GND2")
		(14 "In6.Cu" signal "IN3")
		(16 "In7.Cu" signal "GND3")
		(18 "In8.Cu" signal "VCC")
		(20 "In9.Cu" signal "VCC1")
		(22 "In10.Cu" signal "GND4")
		(24 "In11.Cu" signal "IN4")
		(26 "In12.Cu" signal "GND5")
		(28 "In13.Cu" signal "IN5")
		(30 "In14.Cu" signal "GND6")
		(32 "In15.Cu" signal "IN6")
		(34 "In16.Cu" signal "GND7")
		(2 "B.Cu" signal "BOTTOM")
		(9 "F.Adhes" user "F.Adhesive")
		(11 "B.Adhes" user "B.Adhesive")
		(13 "F.Paste" user "Package Geometry/Pastemask Top")
		(15 "B.Paste" user "Package Geometry/Pastemask Bottom")
		(5 "F.SilkS" user "Ref Des/Silkscreen Top")
		(7 "B.SilkS" user "Ref Des/Silkscreen Bottom")
		(1 "F.Mask" user "Board Geometry/Soldermask Top")
		(3 "B.Mask" user "Board Geometry/Soldermask Bottom")
		(17 "Dwgs.User" user "User.Drawings")
		(19 "Cmts.User" user "User.Comments")
		(21 "Eco1.User" user "User.Eco1")
		(23 "Eco2.User" user "User.Eco2")
		(25 "Edge.Cuts" user "Board Geometry/Outline")
		(27 "Margin" user)
		(31 "F.CrtYd" user "Package Geometry/Place Bound Top")
		(29 "B.CrtYd" user "Package Geometry/Place Bound Bottom")
		(35 "F.Fab" user "Ref Des/Assembly Top")
		(33 "B.Fab" user "Ref Des/Assembly Bottom")
	)
	(footprint ""
		(layer "F.Cu")
		(at 434.06568 -178.069748 180)
		(property "Reference" "PC27"
			(at 0 0 180)
			(layer "F.SilkS")
			(hide yes)
			(effects
				(font
					(size 1.27 1.27)
				)
			)
		)
		(property "Value" ""
			(at 0 0 180)
			(layer "F.Fab")
			(effects
				(font
					(size 1.27 1.27)
				)
			)
		)
		(duplicate_pad_numbers_are_jumpers no)
		(fp_line
			(start 0.7874 0.4064)
			(end -0.7874 0.4064)
			(stroke
				(width 0.1524)
				(type default)
			)
			(layer "F.SilkS")
		)
		(fp_line
			(start 0.7874 -0.4064)
			(end 0.7874 0.4064)
			(stroke
				(width 0.1524)
				(type default)
			)
			(layer "F.SilkS")
		)
		(fp_line
			(start -0.7874 0.4064)
			(end -0.7874 -0.4064)
			(stroke
				(width 0.1524)
				(type default)
			)
			(layer "F.SilkS")
		)
		(fp_line
			(start -0.7874 -0.4064)
			(end 0.7874 -0.4064)
			(stroke
				(width 0.1524)
				(type default)
			)
			(layer "F.SilkS")
		)
		(fp_line
			(start 0.67945 0.3048)
			(end 0.120396 0.3048)
			(stroke
				(width 0.1)
				(type default)
			)
			(layer "F.Fab")
		)
		(fp_line
			(start 0.67945 -0.3048)
			(end 0.67945 0.3048)
			(stroke
				(width 0.1)
				(type default)
			)
			(layer "F.Fab")
		)
		(fp_line
			(start 0.12065 -0.2794)
			(end 0.12065 -0.3048)
			(stroke
				(width 0.1)
				(type default)
			)
			(layer "F.Fab")
		)
		(fp_line
			(start 0.12065 -0.3048)
			(end 0.67945 -0.3048)
			(stroke
				(width 0.1)
				(type default)
			)
			(layer "F.Fab")
		)
		(fp_line
			(start 0.120396 0.3048)
			(end 0.120396 0.2794)
			(stroke
				(width 0.1)
				(type default)
			)
			(layer "F.Fab")
		)
		(fp_line
			(start 0.120396 0.2794)
			(end -0.12065 0.2794)
			(stroke
				(width 0.1)
				(type default)
			)
			(layer "F.Fab")
		)
		(fp_line
			(start -0.12065 0.3048)
			(end -0.67945 0.3048)
			(stroke
				(width 0.1)
				(type default)
			)
			(layer "F.Fab")
		)
		(fp_line
			(start -0.12065 0.2794)
			(end -0.12065 0.3048)
			(stroke
				(width 0.1)
				(type default)
			)
			(layer "F.Fab")
		)
		(fp_line
			(start -0.12065 -0.2794)
			(end 0.12065 -0.2794)
			(stroke
				(width 0.1)
				(type default)
			)
			(layer "F.Fab")
		)
		(fp_line
			(start -0.12065 -0.305054)
			(end -0.12065 -0.2794)
			(stroke
				(width 0.1)
				(type default)
			)
			(layer "F.Fab")
		)
		(fp_line
			(start -0.67945 0.3048)
			(end -0.67945 -0.305054)
			(stroke
				(width 0.1)
				(type default)
			)
			(layer "F.Fab")
		)
		(fp_line
			(start -0.67945 -0.305054)
			(end -0.12065 -0.305054)
			(stroke
				(width 0.1)
				(type default)
			)
			(layer "F.Fab")
		)
		(pad "1" smd circle
			(at -0.40005 0 180)
			(size 0 0)
			(layers "F.Cu" "F.Mask" "F.Paste")
			(net "PVNN_MAIN_CPU0_REF")
		)
		(pad "2" smd circle
			(at 0.40005 0 180)
			(size 0 0)
			(layers "F.Cu" "F.Mask" "F.Paste")
			(net "GND")
		)
	)
	(footprint ""
		(layer "F.Cu")
		(at 485.20985 -216.092532 -90)
		(property "Reference" "X42"
			(at -0.1778 -1.92913 270)
			(unlocked yes)
			(layer "F.SilkS")
			(effects
				(font
					(size 0.7874 0.5842)
					(thickness 0.1524)
				)
				(justify left)
			)
		)
		(property "Value" ""
			(at 0 0 270)
			(layer "F.Fab")
			(effects
				(font
					(size 1.27 1.27)
				)
			)
		)
		(property "Device Type" "TP_TDR_4P_FTS_TH-TP_TDR_4P_DIPA"
			(at 1.30175 1.27 0)
			(unlocked yes)
			(layer "F.Fab")
			(hide yes)
			(effects
				(font
					(size 0.635 0.4064)
					(thickness 0.1524)
				)
			)
		)
		(property "User Part Number" "N_A"
			(at 1.30175 1.27 0)
			(unlocked yes)
			(layer "Cmts.User")
			(hide yes)
			(effects
				(font
					(size 0.635 0.4064)
					(thickness 0.1524)
				)
			)
		)
		(duplicate_pad_numbers_are_jumpers no)
		(fp_line
			(start 0 3.81)
			(end 2.54 3.81)
			(stroke
				(width 0.1524)
				(type default)
			)
			(layer "F.SilkS")
		)
		(fp_line
			(start 2.54 3.81)
			(end 2.54 3.6703)
			(stroke
				(width 0.1524)
				(type default)
			)
			(layer "F.SilkS")
		)
		(fp_line
			(start 0 3.175)
			(end 0 3.81)
			(stroke
				(width 0.1524)
				(type default)
			)
			(layer "F.SilkS")
		)
		(fp_line
			(start 2.54 1.4097)
			(end 2.54 1.1303)
			(stroke
				(width 0.1524)
				(type default)
			)
			(layer "F.SilkS")
		)
		(fp_line
			(start 0 0.635)
			(end 0 1.905)
			(stroke
				(width 0.1524)
				(type default)
			)
			(layer "F.SilkS")
		)
		(fp_line
			(start 2.54 -1.1303)
			(end 2.54 -1.27)
			(stroke
				(width 0.1524)
				(type default)
			)
			(layer "F.SilkS")
		)
		(fp_line
			(start 0 -1.27)
			(end 0 -0.635)
			(stroke
				(width 0.1524)
				(type default)
			)
			(layer "F.SilkS")
		)
		(fp_line
			(start 2.54 -1.27)
			(end 0 -1.27)
			(stroke
				(width 0.1524)
				(type default)
			)
			(layer "F.SilkS")
		)
		(fp_poly
			(pts
				(xy -0.761746 0) (xy -2.285746 -0.762) (xy -2.285746 0.762)
			)
			(stroke
				(width 0)
				(type default)
			)
			(fill yes)
			(layer "F.SilkS")
		)
		(fp_line
			(start 0 3.81)
			(end 2.54 3.81)
			(stroke
				(width 0.1)
				(type default)
			)
			(layer "F.Fab")
		)
		(fp_line
			(start 2.54 3.81)
			(end 2.54 -1.27)
			(stroke
				(width 0.1)
				(type default)
			)
			(layer "F.Fab")
		)
		(fp_line
			(start 0 -1.27)
			(end 0 3.81)
			(stroke
				(width 0.1)
				(type default)
			)
			(layer "F.Fab")
		)
		(fp_line
			(start 2.54 -1.27)
			(end 0 -1.27)
			(stroke
				(width 0.1)
				(type default)
			)
			(layer "F.Fab")
		)
		(fp_poly
			(pts
				(xy -0.761746 0) (xy -2.285746 -0.762) (xy -2.285746 0.762)
			)
			(stroke
				(width 0)
				(type default)
			)
			(fill yes)
			(layer "F.Fab")
		)
		(pad "1" thru_hole circle
			(at 0 0 270)
			(size 1.0033 1.0033)
			(drill 0.249936)
			(layers "*.Cu" "*.Mask")
			(remove_unused_layers no)
			(net "TDR_DIFF_85_NECK_IN1_DN")
			(clearance 0.10795)
			(thermal_gap 0.10795)
			(padstack
				(mode front_inner_back)
				(layer "Inner"
					(shape circle)
					(size 0.8001 0.8001)
					(clearance 0.1524)
				)
				(layer "B.Cu"
					(shape circle)
					(size 1.0033 1.0033)
					(clearance 0.10795)
				)
			)
		)
		(pad "2" thru_hole circle
			(at 2.54 0 270)
			(size 1.9939 1.9939)
			(drill 0.249936)
			(layers "*.Cu" "*.Mask")
			(remove_unused_layers no)
			(net "T1_GND")
			(clearance 0.10795)
			(thermal_gap 0.10795)
			(padstack
				(mode front_inner_back)
				(layer "Inner"
					(shape circle)
					(size 0.8001 0.8001)
					(clearance 0.1524)
				)
				(layer "B.Cu"
					(shape circle)
					(size 1.9939 1.9939)
					(clearance 0.10795)
				)
			)
		)
		(pad "3" thru_hole circle
			(at 2.54 2.54 270)
			(size 1.9939 1.9939)
			(drill 0.249936)
			(layers "*.Cu" "*.Mask")
			(remove_unused_layers no)
			(net "T1_GND")
			(clearance 0.10795)
			(thermal_gap 0.10795)
			(padstack
				(mode front_inner_back)
				(layer "Inner"
					(shape circle)
					(size 0.8001 0.8001)
					(clearance 0.1524)
				)
				(layer "B.Cu"
					(shape circle)
					(size 1.9939 1.9939)
					(clearance 0.10795)
				)
			)
		)
		(pad "4" thru_hole circle
			(at 0 2.54 270)
			(size 1.0033 1.0033)
			(drill 0.249936)
			(layers "*.Cu" "*.Mask")
			(remove_unused_layers no)
			(net "TDR_DIFF_85_NECK_IN1_DP")
			(clearance 0.10795)
			(thermal_gap 0.10795)
			(padstack
				(mode front_inner_back)
				(layer "Inner"
					(shape circle)
					(size 0.8001 0.8001)
					(clearance 0.1524)
				)
				(layer "B.Cu"
					(shape circle)
					(size 1.0033 1.0033)
					(clearance 0.10795)
				)
			)
		)
	)
)
